# BASEBOARD_FAB2 (Tioga Pass) — schematic netlist excerpt (pin names and nets, part order shuffled) for the footprints in the layout excerpt that follows; sources: Cadence DE-HDL packaged netlist, KiCad conversion of Wiwynn_Tioga_Pass_MB.brd

R25W23  120R2F-GP  1%  pkg RCL_GP  page 151 : \1\ = GND ; \2\ = BMC_M_A11
R7D42  RES  4.75K 1% CHIP  pkg 0402  page 191 : A = P3V3_STBY ; B = PU_FAB2_MARKER_CPLD
C4D10  CAP  1.0UF 16V 10% X6S  pkg 0402  page 203 : A = VR_FET_SW_P12V_STBY_PVCCIN_CPU0 ; B = GND

(kicad_pcb
	(version 20260206)
	(generator "pcbnew")
	(generator_version "10.0")
	(general
		(thickness 1.6)
		(legacy_teardrops no)
	)
	(paper "A4")
	(title_block
		(title "Wiwynn_Tioga_Pass_MB.brd")
		(comment 1 "Tioga Pass / footprints 1647-1649 of 4770")
	)
	(layers
		(0 "F.Cu" signal "TOP")
		(4 "In1.Cu" signal "L2GND")
		(6 "In2.Cu" signal "L3")
		(8 "In3.Cu" signal "L4GND")
		(10 "In4.Cu" signal "L5")
		(12 "In5.Cu" signal "L6GND")
		(14 "In6.Cu" signal "L7VCC")
		(16 "In7.Cu" signal "L8VCC")
		(18 "In8.Cu" signal "L9GND")
		(20 "In9.Cu" signal "L10")
		(22 "In10.Cu" signal "L11GND")
		(24 "In11.Cu" signal "L12")
		(26 "In12.Cu" signal "L13GND")
		(2 "B.Cu" signal "BOTTOM")
		(9 "F.Adhes" user "F.Adhesive")
		(11 "B.Adhes" user "B.Adhesive")
		(13 "F.Paste" user "Package Geometry/Pastemask Top")
		(15 "B.Paste" user "Package Geometry/Pastemask Bottom")
		(5 "F.SilkS" user "Ref Des/Silkscreen Top")
		(7 "B.SilkS" user "Ref Des/Silkscreen Bottom")
		(1 "F.Mask" user "Board Geometry/Soldermask Top")
		(3 "B.Mask" user "Board Geometry/Soldermask Bottom")
		(17 "Dwgs.User" user "User.Drawings")
		(19 "Cmts.User" user "User.Comments")
		(21 "Eco1.User" user "User.Eco1")
		(23 "Eco2.User" user "User.Eco2")
		(25 "Edge.Cuts" user "Board Geometry/Outline")
		(27 "Margin" user)
		(31 "F.CrtYd" user "Package Geometry/Place Bound Top")
		(29 "B.CrtYd" user "Package Geometry/Place Bound Bottom")
		(35 "F.Fab" user "Ref Des/Assembly Top")
		(33 "B.Fab" user "Ref Des/Assembly Bottom")
	)
	(footprint ""
		(layer "F.Cu")
		(at 194.7418 -84.3026 -90)
		(property "Reference" "C4D10"
			(at 0 0 270)
			(layer "F.SilkS")
			(hide yes)
			(effects
				(font
					(size 1.27 1.27)
				)
			)
		)
		(property "Value" ""
			(at 0 0 270)
			(layer "F.Fab")
			(effects
				(font
					(size 1.27 1.27)
				)
			)
		)
		(duplicate_pad_numbers_are_jumpers no)
		(fp_poly
			(pts
				(xy 0.3048 -0.1016) (xy 0.3048 0.9906) (xy -0.3048 0.9906) (xy -0.3048 -0.1016)
			)
			(stroke
				(width 0)
				(type default)
			)
			(fill no)
			(layer "F.CrtYd")
		)
		(fp_line
			(start -0.3048 0.9906)
			(end 0.3048 0.9906)
			(stroke
				(width 0.1)
				(type default)
			)
			(layer "F.Fab")
		)
		(fp_line
			(start 0.3048 0.9906)
			(end 0.3048 -0.1016)
			(stroke
				(width 0.1)
				(type default)
			)
			(layer "F.Fab")
		)
		(fp_line
			(start -0.3048 -0.1016)
			(end -0.3048 0.9906)
			(stroke
				(width 0.1)
				(type default)
			)
			(layer "F.Fab")
		)
		(fp_line
			(start 0.3048 -0.1016)
			(end -0.3048 -0.1016)
			(stroke
				(width 0.1)
				(type default)
			)
			(layer "F.Fab")
		)
		(pad "1" smd rect
			(at 0 0 270)
			(size 0.508 0.508)
			(layers "F.Cu" "F.Mask" "F.Paste")
			(net "VR_FET_SW_P12V_STBY_PVCCIN_CPU0")
		)
		(pad "2" smd rect
			(at 0 0.889 270)
			(size 0.508 0.508)
			(layers "F.Cu" "F.Mask" "F.Paste")
			(net "GND")
		)
		(zone
			(layer "F.Cu")
			(hatch none 0.5)
			(connect_pads
				(clearance 0)
			)
			(min_thickness 0.25)
			(keepout
				(tracks not_allowed)
				(vias allowed)
				(pads allowed)
				(copperpour not_allowed)
				(footprints allowed)
			)
			(placement
				(enabled no)
				(sheetname "")
			)
			(fill
				(thermal_gap 0.5)
				(thermal_bridge_width 0.5)
				(island_removal_mode 0)
			)
			(polygon
				(pts
					(xy 194.1068 -84.5566) (xy 194.1068 -84.0486) (xy 194.4878 -84.0486) (xy 194.4878 -84.5566)
				)
			)
		)
		(zone
			(layer "F.Cu")
			(hatch none 0.5)
			(connect_pads
				(clearance 0)
			)
			(min_thickness 0.25)
			(keepout
				(tracks allowed)
				(vias not_allowed)
				(pads allowed)
				(copperpour not_allowed)
				(footprints allowed)
			)
			(placement
				(enabled no)
				(sheetname "")
			)
			(fill
				(thermal_gap 0.5)
				(thermal_bridge_width 0.5)
				(island_removal_mode 0)
			)
			(polygon
				(pts
					(xy 194.4878 -84.5566) (xy 194.4878 -84.0486) (xy 194.1068 -84.0486) (xy 194.1068 -84.5566)
				)
			)
		)
	)
	(footprint ""
		(layer "F.Cu")
		(at 449.69938 -38.2905 90)
		(property "Reference" "R25W23"
			(at 0 0 90)
			(layer "F.SilkS")
			(hide yes)
			(effects
				(font
					(size 1.27 1.27)
				)
			)
		)
		(property "Value" "*"
			(at 0.064008 -4.108196 90)
			(unlocked yes)
			(layer "F.Fab")
			(hide yes)
			(effects
				(font
					(size 1.27 1.016)
					(thickness 0.1524)
				)
			)
		)
		(property "Device Type" "120R2F-GP_RCL_GP-120R2F-GP,64.A"
			(at 0.064008 -5.632196 90)
			(unlocked yes)
			(layer "F.Fab")
			(hide yes)
			(effects
				(font
					(size 1.27 1.016)
					(thickness 0.1524)
				)
			)
		)
		(duplicate_pad_numbers_are_jumpers no)
		(fp_line
			(start 0.508 -0.9398)
			(end -0.508 -0.9398)
			(stroke
				(width 0.1524)
				(type default)
			)
			(layer "F.SilkS")
		)
		(fp_line
			(start -0.508 -0.9398)
			(end -0.508 0.9398)
			(stroke
				(width 0.1524)
				(type default)
			)
			(layer "F.SilkS")
		)
		(fp_rect
			(start -0.508 0.9398)
			(end 0.508 -0.9398)
			(stroke
				(width 0)
				(type default)
			)
			(fill no)
			(layer "F.CrtYd")
		)
		(fp_rect
			(start -0.508 0.9398)
			(end 0.508 -0.9398)
			(stroke
				(width 0)
				(type default)
			)
			(fill no)
			(layer "F.Fab")
		)
		(pad "1" smd custom
			(at 0 -0.4445 90)
			(size 0.1397 0.1397)
			(layers "F.Cu" "F.Mask" "F.Paste")
			(net "GND")
			(options
				(clearance outline)
				(anchor circle)
			)
			(primitives
				(gr_poly
					(pts
						(arc
							(start -0.1778 -0.2794)
							(mid -0.249642 -0.249642)
							(end -0.2794 -0.1778)
						)
						(arc
							(start -0.2794 0.1778)
							(mid -0.249642 0.249642)
							(end -0.1778 0.2794)
						)
						(arc
							(start 0.1778 0.2794)
							(mid 0.249642 0.249642)
							(end 0.2794 0.1778)
						)
						(arc
							(start 0.2794 -0.1778)
							(mid 0.249642 -0.249642)
							(end 0.1778 -0.2794)
						)
					)
					(width 0)
					(fill yes)
				)
			)
		)
		(pad "2" smd custom
			(at 0 0.4445 90)
			(size 0.1397 0.1397)
			(layers "F.Cu" "F.Mask" "F.Paste")
			(net "BMC_M_A11")
			(options
				(clearance outline)
				(anchor circle)
			)
			(primitives
				(gr_poly
					(pts
						(arc
							(start -0.1778 -0.2794)
							(mid -0.249642 -0.249642)
							(end -0.2794 -0.1778)
						)
						(arc
							(start -0.2794 0.1778)
							(mid -0.249642 0.249642)
							(end -0.1778 0.2794)
						)
						(arc
							(start 0.1778 0.2794)
							(mid 0.249642 0.249642)
							(end 0.2794 0.1778)
						)
						(arc
							(start 0.2794 -0.1778)
							(mid 0.249642 -0.249642)
							(end 0.1778 -0.2794)
						)
					)
					(width 0)
					(fill yes)
				)
			)
		)
	)
	(footprint ""
		(layer "F.Cu")
		(at 363.249718 -72.133206 180)
		(property "Reference" "R7D42"
			(at 0 0 180)
			(layer "F.SilkS")
			(hide yes)
			(effects
				(font
					(size 1.27 1.27)
				)
			)
		)
		(property "Value" ""
			(at 0 0 180)
			(layer "F.Fab")
			(effects
				(font
					(size 1.27 1.27)
				)
			)
		)
		(duplicate_pad_numbers_are_jumpers no)
		(fp_poly
			(pts
				(xy -0.2794 -0.1016) (xy 0.2794 -0.1016) (xy 0.2794 0.9906) (xy -0.2794 0.9906)
			)
			(stroke
				(width 0)
				(type default)
			)
			(fill no)
			(layer "F.CrtYd")
		)
		(fp_line
			(start 0.2794 0.9906)
			(end 0.2794 -0.1016)
			(stroke
				(width 0.1)
				(type default)
			)
			(layer "F.Fab")
		)
		(fp_line
			(start 0.2794 -0.1016)
			(end -0.2794 -0.1016)
			(stroke
				(width 0.1)
				(type default)
			)
			(layer "F.Fab")
		)
		(fp_line
			(start -0.2794 0.9906)
			(end 0.2794 0.9906)
			(stroke
				(width 0.1)
				(type default)
			)
			(layer "F.Fab")
		)
		(fp_line
			(start -0.2794 -0.1016)
			(end -0.2794 0.9906)
			(stroke
				(width 0.1)
				(type default)
			)
			(layer "F.Fab")
		)
		(pad "1" smd rect
			(at 0 0 180)
			(size 0.508 0.508)
			(layers "F.Cu" "F.Mask" "F.Paste")
			(net "P3V3_STBY")
		)
		(pad "2" smd rect
			(at 0 0.889 180)
			(size 0.508 0.508)
			(layers "F.Cu" "F.Mask" "F.Paste")
			(net "PU_FAB2_MARKER_CPLD")
		)
		(zone
			(layer "F.Cu")
			(hatch none 0.5)
			(connect_pads
				(clearance 0)
			)
			(min_thickness 0.25)
			(keepout
				(tracks not_allowed)
				(vias allowed)
				(pads allowed)
				(copperpour not_allowed)
				(footprints allowed)
			)
			(placement
				(enabled no)
				(sheetname "")
			)
			(fill
				(thermal_gap 0.5)
				(thermal_bridge_width 0.5)
				(island_removal_mode 0)
			)
			(polygon
				(pts
					(xy 363.503718 -72.768206) (xy 362.995718 -72.768206) (xy 362.995718 -72.387206) (xy 363.503718 -72.387206)
				)
			)
		)
		(zone
			(layer "F.Cu")
			(hatch none 0.5)
			(connect_pads
				(clearance 0)
			)
			(min_thickness 0.25)
			(keepout
				(tracks allowed)
				(vias not_allowed)
				(pads allowed)
				(copperpour not_allowed)
				(footprints allowed)
			)
			(placement
				(enabled no)
				(sheetname "")
			)
			(fill
				(thermal_gap 0.5)
				(thermal_bridge_width 0.5)
				(island_removal_mode 0)
			)
			(polygon
				(pts
					(xy 363.503718 -72.387206) (xy 362.995718 -72.387206) (xy 362.995718 -72.768206) (xy 363.503718 -72.768206)
				)
			)
		)
	)
)
